<schema xmlns="http://www.cadence.com/spb/csschema"
	xmlns:xsi="http://www.w3.org/2001/XMLSchema-instance"
	xsi:schemaLocation="http://www.cadence.com/spb/csschema CSSchema002.xsd">
  <header>
    <schemaVersion>16.5</schemaVersion>
    <creatorTool>conceptHDL</creatorTool>
    <modifierTool>conceptHDL</modifierTool>
    <modificationTime>2011-10-25T14:31:39</modificationTime>
    <savedLibrary>mstr_symbols</savedLibrary>
  </header>
  <designs>
    <design schemaType="nameBased" name="p5v_stby" view="sch_1">
      <lastids>
        <netid>4</netid>
      </lastids>
      <cells>
      </cells>
      <nets>
        <net>
          <id>N1</id>
          <name>g</name>
          <scope>interface</scope>
          <direction>inout</direction>
        </net>
        <net>
          <id>N2</id>
          <name>page1_g</name>
        </net>
        <net>
          <id>N4</id>
          <name>page1_p5v_stby</name>
        </net>
        <net>
          <id>N3</id>
          <name>p5v_stby</name>
          <scope>global</scope>
        </net>
      </nets>
      <aliases>
        <alias net1="N2" lsb1="-1" msb1="-1" net2="N1" lsb2="-1" msb2="-1" />
        <alias net1="N4" lsb1="-1" msb1="-1" net2="N2" lsb2="-1" msb2="-1" />
        <alias net1="N4" lsb1="-1" msb1="-1" net2="N3" lsb2="-1" msb2="-1" />
      </aliases>
      <differentialnets>
      </differentialnets>
      <differentialbusnets>
      </differentialbusnets>
      <netgroups>
      </netgroups>
      <netinterfaces>
      </netinterfaces>
      <instances>
      </instances>
      <templateresolutions>
      </templateresolutions>
      <templateinstances>
      </templateinstances>
      <extensions>
        <extension name="schematic_extension">
        <schematicExtension>
        <netScopes>
          <netScope ref="g">
            <pageScope number="1">
              <scope>interface</scope>
              <direction>unknown</direction>
            </pageScope>
          </netScope>
          <netScope ref="p5v_stby">
            <pageScope number="1">
              <scope>global</scope>
            </pageScope>
          </netScope>
        </netScopes>
        <pages>
          <page number="1">
            <physicalPageNumber>1</physicalPageNumber>
            <errorStatus>false</errorStatus>
            <nets>
              <net ref="g"></net>
              <net ref="p5v_stby"></net>
            </nets>
            <instances>
            </instances>
          </page>
        </pages>
      </schematicExtension>
        </extension>
      </extensions>
    </design>
  </designs>
</schema>
